(kicad_pcb
	(version 20260206)
	(generator "pcbnew")
	(generator_version "10.0")
	(general
		(thickness 1.6)
		(legacy_teardrops no)
	)
	(paper "A4")
	(title_block
		(title "baseboard — 13948-1b.1110WZS1818.brd")
		(comment 1 "Honey Badger (Wiwynn) / footprints 817-822 of 2523")
	)
	(layers
		(0 "F.Cu" signal "TOP")
		(4 "In1.Cu" signal "L2GND")
		(6 "In2.Cu" signal "L3")
		(8 "In3.Cu" signal "L4VCC")
		(10 "In4.Cu" signal "L5VCC")
		(12 "In5.Cu" signal "L6")
		(14 "In6.Cu" signal "L7GND")
		(2 "B.Cu" signal "BOTTOM")
		(9 "F.Adhes" user "F.Adhesive")
		(11 "B.Adhes" user "B.Adhesive")
		(13 "F.Paste" user "Package Geometry/Pastemask Top")
		(15 "B.Paste" user "Package Geometry/Pastemask Bottom")
		(5 "F.SilkS" user "Ref Des/Silkscreen Top")
		(7 "B.SilkS" user "Ref Des/Silkscreen Bottom")
		(1 "F.Mask" user "Board Geometry/Soldermask Top")
		(3 "B.Mask" user "Board Geometry/Soldermask Bottom")
		(17 "Dwgs.User" user "User.Drawings")
		(19 "Cmts.User" user "User.Comments")
		(21 "Eco1.User" user "User.Eco1")
		(23 "Eco2.User" user "User.Eco2")
		(25 "Edge.Cuts" user "Board Geometry/Outline")
		(27 "Margin" user)
		(31 "F.CrtYd" user "Package Geometry/Place Bound Top")
		(29 "B.CrtYd" user "Package Geometry/Place Bound Bottom")
		(35 "F.Fab" user "Ref Des/Assembly Top")
		(33 "B.Fab" user "Ref Des/Assembly Bottom")
	)
	(footprint ""
		(layer "F.Cu")
		(at 194.491864 -46.681136 90)
		(property "Reference" "Q7"
			(at 0 0 90)
			(layer "F.SilkS")
			(hide yes)
			(effects
				(font
					(size 1.27 1.27)
				)
			)
		)
		(property "Value" "2N7002A-7-GP"
			(at 0.127 -8.9662 90)
			(unlocked yes)
			(layer "F.Fab")
			(hide yes)
			(effects
				(font
					(size 1.016 1.016)
					(thickness 0.1524)
				)
			)
		)
		(property "Device Type" "SOT23DGS2D4H48"
			(at 0.127 -10.4902 90)
			(unlocked yes)
			(layer "F.Fab")
			(hide yes)
			(effects
				(font
					(size 1.016 1.016)
					(thickness 0.1524)
				)
			)
		)
		(duplicate_pad_numbers_are_jumpers no)
		(fp_line
			(start 1.651 -1.778)
			(end -1.651 -1.778)
			(stroke
				(width 0.1524)
				(type default)
			)
			(layer "F.SilkS")
		)
		(fp_line
			(start -1.651 -1.778)
			(end -1.651 1.778)
			(stroke
				(width 0.1524)
				(type default)
			)
			(layer "F.SilkS")
		)
		(fp_line
			(start 1.651 1.778)
			(end 1.651 -1.778)
			(stroke
				(width 0.1524)
				(type default)
			)
			(layer "F.SilkS")
		)
		(fp_line
			(start -1.651 1.778)
			(end 1.651 1.778)
			(stroke
				(width 0.1524)
				(type default)
			)
			(layer "F.SilkS")
		)
		(fp_poly
			(pts
				(xy -1.778 1.8796) (xy -1.778 -1.8796) (xy 1.778 -1.8796) (xy 1.778 1.8796)
			)
			(stroke
				(width 0)
				(type default)
			)
			(fill no)
			(layer "F.CrtYd")
		)
		(fp_poly
			(pts
				(xy -1.778 1.8796) (xy -1.778 -1.8796) (xy 1.778 -1.8796) (xy 1.778 1.8796)
			)
			(stroke
				(width 0)
				(type default)
			)
			(fill no)
			(layer "F.Fab")
		)
		(pad "D" smd custom
			(at 0 -0.9525 90)
			(size 0.1905 0.1905)
			(layers "F.Cu" "F.Mask" "F.Paste")
			(net "PRSNT_MSB_AND_1")
			(options
				(clearance outline)
				(anchor circle)
			)
			(primitives
				(gr_poly
					(pts
						(arc
							(start -0.1778 0.5715)
							(mid -0.321484 0.511984)
							(end -0.381 0.3683)
						)
						(arc
							(start -0.381 -0.3683)
							(mid -0.321484 -0.511984)
							(end -0.1778 -0.5715)
						)
						(arc
							(start 0.1778 -0.5715)
							(mid 0.321484 -0.511984)
							(end 0.381 -0.3683)
						)
						(arc
							(start 0.381 0.3683)
							(mid 0.321484 0.511984)
							(end 0.1778 0.5715)
						)
					)
					(width 0)
					(fill yes)
				)
			)
		)
		(pad "G" smd custom
			(at -0.98425 0.9525 90)
			(size 0.1905 0.1905)
			(layers "F.Cu" "F.Mask" "F.Paste")
			(net "PRSNT_MSB_B81")
			(options
				(clearance outline)
				(anchor circle)
			)
			(primitives
				(gr_poly
					(pts
						(arc
							(start -0.1778 0.5715)
							(mid -0.321484 0.511984)
							(end -0.381 0.3683)
						)
						(arc
							(start -0.381 -0.3683)
							(mid -0.321484 -0.511984)
							(end -0.1778 -0.5715)
						)
						(arc
							(start 0.1778 -0.5715)
							(mid 0.321484 -0.511984)
							(end 0.381 -0.3683)
						)
						(arc
							(start 0.381 0.3683)
							(mid 0.321484 0.511984)
							(end 0.1778 0.5715)
						)
					)
					(width 0)
					(fill yes)
				)
			)
		)
		(pad "S" smd custom
			(at 0.98425 0.9525 90)
			(size 0.1905 0.1905)
			(layers "F.Cu" "F.Mask" "F.Paste")
			(net "GND")
			(options
				(clearance outline)
				(anchor circle)
			)
			(primitives
				(gr_poly
					(pts
						(arc
							(start -0.1778 0.5715)
							(mid -0.321484 0.511984)
							(end -0.381 0.3683)
						)
						(arc
							(start -0.381 -0.3683)
							(mid -0.321484 -0.511984)
							(end -0.1778 -0.5715)
						)
						(arc
							(start 0.1778 -0.5715)
							(mid 0.321484 -0.511984)
							(end 0.381 -0.3683)
						)
						(arc
							(start 0.381 0.3683)
							(mid 0.321484 0.511984)
							(end 0.1778 0.5715)
						)
					)
					(width 0)
					(fill yes)
				)
			)
		)
	)
	(footprint ""
		(layer "F.Cu")
		(at 117.964966 -45.847 -90)
		(property "Reference" "SR668"
			(at 0 0 270)
			(layer "F.SilkS")
			(hide yes)
			(effects
				(font
					(size 1.27 1.27)
				)
			)
		)
		(property "Value" "10KR2F-2-GP"
			(at 0.064008 -3.993896 270)
			(unlocked yes)
			(layer "F.Fab")
			(hide yes)
			(effects
				(font
					(size 1.016 1.016)
					(thickness 0.1524)
				)
			)
		)
		(property "Device Type" "R402H16"
			(at 0.064008 -5.517896 270)
			(unlocked yes)
			(layer "F.Fab")
			(hide yes)
			(effects
				(font
					(size 1.016 1.016)
					(thickness 0.1524)
				)
			)
		)
		(duplicate_pad_numbers_are_jumpers no)
		(fp_line
			(start -0.508 -0.9398)
			(end -0.508 0.9398)
			(stroke
				(width 0.1524)
				(type default)
			)
			(layer "F.SilkS")
		)
		(fp_line
			(start 0.508 -0.9398)
			(end -0.508 -0.9398)
			(stroke
				(width 0.1524)
				(type default)
			)
			(layer "F.SilkS")
		)
		(fp_rect
			(start -0.508 0.9398)
			(end 0.508 -0.9398)
			(stroke
				(width 0)
				(type default)
			)
			(fill no)
			(layer "F.CrtYd")
		)
		(fp_rect
			(start -0.508 0.9398)
			(end 0.508 -0.9398)
			(stroke
				(width 0)
				(type default)
			)
			(fill no)
			(layer "F.Fab")
		)
		(pad "1" smd custom
			(at 0 -0.4445 270)
			(size 0.1397 0.1397)
			(layers "F.Cu" "F.Mask" "F.Paste")
			(net "P1V8_C")
			(options
				(clearance outline)
				(anchor circle)
			)
			(primitives
				(gr_poly
					(pts
						(arc
							(start -0.1778 -0.2794)
							(mid -0.249642 -0.249642)
							(end -0.2794 -0.1778)
						)
						(arc
							(start -0.2794 0.1778)
							(mid -0.249642 0.249642)
							(end -0.1778 0.2794)
						)
						(arc
							(start 0.1778 0.2794)
							(mid 0.249642 0.249642)
							(end 0.2794 0.1778)
						)
						(arc
							(start 0.2794 -0.1778)
							(mid 0.249642 -0.249642)
							(end 0.1778 -0.2794)
						)
					)
					(width 0)
					(fill yes)
				)
			)
		)
		(pad "2" smd custom
			(at 0 0.4445 270)
			(size 0.1397 0.1397)
			(layers "F.Cu" "F.Mask" "F.Paste")
			(net "SYS_CORE_TRI#")
			(options
				(clearance outline)
				(anchor circle)
			)
			(primitives
				(gr_poly
					(pts
						(arc
							(start -0.1778 -0.2794)
							(mid -0.249642 -0.249642)
							(end -0.2794 -0.1778)
						)
						(arc
							(start -0.2794 0.1778)
							(mid -0.249642 0.249642)
							(end -0.1778 0.2794)
						)
						(arc
							(start 0.1778 0.2794)
							(mid 0.249642 0.249642)
							(end 0.2794 0.1778)
						)
						(arc
							(start 0.2794 -0.1778)
							(mid 0.249642 -0.249642)
							(end 0.1778 -0.2794)
						)
					)
					(width 0)
					(fill yes)
				)
			)
		)
	)
	(footprint ""
		(layer "F.Cu")
		(at 97.536 -233.807)
		(property "Reference" "R660"
			(at 0 0 0)
			(layer "F.SilkS")
			(hide yes)
			(effects
				(font
					(size 1.27 1.27)
				)
			)
		)
		(property "Value" "0R2J-2-GP"
			(at 0.064008 -3.993896 0)
			(unlocked yes)
			(layer "F.Fab")
			(hide yes)
			(effects
				(font
					(size 1.016 1.016)
					(thickness 0.1524)
				)
			)
		)
		(property "Device Type" "R402H16"
			(at 0.064008 -5.517896 0)
			(unlocked yes)
			(layer "F.Fab")
			(hide yes)
			(effects
				(font
					(size 1.016 1.016)
					(thickness 0.1524)
				)
			)
		)
		(duplicate_pad_numbers_are_jumpers no)
		(fp_line
			(start -0.508 -0.9398)
			(end -0.508 0.9398)
			(stroke
				(width 0.1524)
				(type default)
			)
			(layer "F.SilkS")
		)
		(fp_line
			(start 0.508 -0.9398)
			(end -0.508 -0.9398)
			(stroke
				(width 0.1524)
				(type default)
			)
			(layer "F.SilkS")
		)
		(fp_rect
			(start -0.508 0.9398)
			(end 0.508 -0.9398)
			(stroke
				(width 0)
				(type default)
			)
			(fill no)
			(layer "F.CrtYd")
		)
		(fp_rect
			(start -0.508 0.9398)
			(end 0.508 -0.9398)
			(stroke
				(width 0)
				(type default)
			)
			(fill no)
			(layer "F.Fab")
		)
		(pad "1" smd custom
			(at 0 -0.4445)
			(size 0.1397 0.1397)
			(layers "F.Cu" "F.Mask" "F.Paste")
			(net "SAS_FAULT_LED8")
			(options
				(clearance outline)
				(anchor circle)
			)
			(primitives
				(gr_poly
					(pts
						(arc
							(start -0.1778 -0.2794)
							(mid -0.249642 -0.249642)
							(end -0.2794 -0.1778)
						)
						(arc
							(start -0.2794 0.1778)
							(mid -0.249642 0.249642)
							(end -0.1778 0.2794)
						)
						(arc
							(start 0.1778 0.2794)
							(mid 0.249642 0.249642)
							(end 0.2794 0.1778)
						)
						(arc
							(start 0.2794 -0.1778)
							(mid 0.249642 -0.249642)
							(end 0.1778 -0.2794)
						)
					)
					(width 0)
					(fill yes)
				)
			)
		)
		(pad "2" smd custom
			(at 0 0.4445)
			(size 0.1397 0.1397)
			(layers "F.Cu" "F.Mask" "F.Paste")
			(net "SAS_HDD_LED_8")
			(options
				(clearance outline)
				(anchor circle)
			)
			(primitives
				(gr_poly
					(pts
						(arc
							(start -0.1778 -0.2794)
							(mid -0.249642 -0.249642)
							(end -0.2794 -0.1778)
						)
						(arc
							(start -0.2794 0.1778)
							(mid -0.249642 0.249642)
							(end -0.1778 0.2794)
						)
						(arc
							(start 0.1778 0.2794)
							(mid 0.249642 0.249642)
							(end 0.2794 0.1778)
						)
						(arc
							(start 0.2794 -0.1778)
							(mid 0.249642 -0.249642)
							(end 0.1778 -0.2794)
						)
					)
					(width 0)
					(fill yes)
				)
			)
		)
	)
	(footprint ""
		(layer "F.Cu")
		(at 333.912718 -154.409648 90)
		(property "Reference" "R217"
			(at 0 0 90)
			(layer "F.SilkS")
			(hide yes)
			(effects
				(font
					(size 1.27 1.27)
				)
			)
		)
		(property "Value" "4K7R2F-GP"
			(at 0.064008 -3.993896 90)
			(unlocked yes)
			(layer "F.Fab")
			(hide yes)
			(effects
				(font
					(size 1.016 1.016)
					(thickness 0.1524)
				)
			)
		)
		(property "Device Type" "R402H16"
			(at 0.064008 -5.517896 90)
			(unlocked yes)
			(layer "F.Fab")
			(hide yes)
			(effects
				(font
					(size 1.016 1.016)
					(thickness 0.1524)
				)
			)
		)
		(duplicate_pad_numbers_are_jumpers no)
		(fp_line
			(start 0.508 -0.9398)
			(end -0.508 -0.9398)
			(stroke
				(width 0.1524)
				(type default)
			)
			(layer "F.SilkS")
		)
		(fp_line
			(start -0.508 -0.9398)
			(end -0.508 0.9398)
			(stroke
				(width 0.1524)
				(type default)
			)
			(layer "F.SilkS")
		)
		(fp_rect
			(start -0.508 0.9398)
			(end 0.508 -0.9398)
			(stroke
				(width 0)
				(type default)
			)
			(fill no)
			(layer "F.CrtYd")
		)
		(fp_rect
			(start -0.508 0.9398)
			(end 0.508 -0.9398)
			(stroke
				(width 0)
				(type default)
			)
			(fill no)
			(layer "F.Fab")
		)
		(pad "1" smd custom
			(at 0 -0.4445 90)
			(size 0.1397 0.1397)
			(layers "F.Cu" "F.Mask" "F.Paste")
			(net "P3V3_STBY")
			(options
				(clearance outline)
				(anchor circle)
			)
			(primitives
				(gr_poly
					(pts
						(arc
							(start -0.1778 -0.2794)
							(mid -0.249642 -0.249642)
							(end -0.2794 -0.1778)
						)
						(arc
							(start -0.2794 0.1778)
							(mid -0.249642 0.249642)
							(end -0.1778 0.2794)
						)
						(arc
							(start 0.1778 0.2794)
							(mid 0.249642 0.249642)
							(end 0.2794 0.1778)
						)
						(arc
							(start 0.2794 -0.1778)
							(mid 0.249642 -0.249642)
							(end 0.1778 -0.2794)
						)
					)
					(width 0)
					(fill yes)
				)
			)
		)
		(pad "2" smd custom
			(at 0 0.4445 90)
			(size 0.1397 0.1397)
			(layers "F.Cu" "F.Mask" "F.Paste")
			(net "USB_OCS_N4")
			(options
				(clearance outline)
				(anchor circle)
			)
			(primitives
				(gr_poly
					(pts
						(arc
							(start -0.1778 -0.2794)
							(mid -0.249642 -0.249642)
							(end -0.2794 -0.1778)
						)
						(arc
							(start -0.2794 0.1778)
							(mid -0.249642 0.249642)
							(end -0.1778 0.2794)
						)
						(arc
							(start 0.1778 0.2794)
							(mid 0.249642 0.249642)
							(end 0.2794 0.1778)
						)
						(arc
							(start 0.2794 -0.1778)
							(mid 0.249642 -0.249642)
							(end 0.1778 -0.2794)
						)
					)
					(width 0)
					(fill yes)
				)
			)
		)
	)
	(footprint ""
		(layer "F.Cu")
		(at 297.163236 -147.617688)
		(property "Reference" "X1"
			(at 0 0 0)
			(layer "F.SilkS")
			(hide yes)
			(effects
				(font
					(size 1.27 1.27)
				)
			)
		)
		(property "Value" "OSC-50MHZ-8-GP-U"
			(at -5.183886 1.282192 0)
			(unlocked yes)
			(layer "F.Fab")
			(hide yes)
			(effects
				(font
					(size 1.016 1.016)
					(thickness 0.1524)
				)
			)
		)
		(property "Device Type" "S-OSC4-7349H75"
			(at -5.183886 -0.241808 0)
			(unlocked yes)
			(layer "F.Fab")
			(hide yes)
			(effects
				(font
					(size 1.016 1.016)
					(thickness 0.1524)
				)
			)
		)
		(duplicate_pad_numbers_are_jumpers no)
		(fp_line
			(start -3.9878 2.0447)
			(end -3.9878 3.3147)
			(stroke
				(width 0.3302)
				(type default)
			)
			(layer "F.SilkS")
		)
		(fp_line
			(start -3.9878 3.3147)
			(end -2.7178 3.3147)
			(stroke
				(width 0.3302)
				(type default)
			)
			(layer "F.SilkS")
		)
		(fp_line
			(start -3.8989 -3.2131)
			(end 3.8989 -3.2131)
			(stroke
				(width 0.1524)
				(type default)
			)
			(layer "F.SilkS")
		)
		(fp_line
			(start -3.8989 3.2131)
			(end -3.8989 -3.2131)
			(stroke
				(width 0.1524)
				(type default)
			)
			(layer "F.SilkS")
		)
		(fp_line
			(start 3.8989 -3.2131)
			(end 3.8989 3.2131)
			(stroke
				(width 0.1524)
				(type default)
			)
			(layer "F.SilkS")
		)
		(fp_line
			(start 3.8989 3.2131)
			(end -3.8989 3.2131)
			(stroke
				(width 0.1524)
				(type default)
			)
			(layer "F.SilkS")
		)
		(fp_poly
			(pts
				(xy -4.879848 1.931924) (xy -4.879848 3.201924) (xy -4.244848 2.566924)
			)
			(stroke
				(width 0)
				(type default)
			)
			(fill yes)
			(layer "F.SilkS")
		)
		(fp_rect
			(start -3.6449 2.4511)
			(end 3.6449 -2.4511)
			(stroke
				(width 0)
				(type default)
			)
			(fill no)
			(layer "F.CrtYd")
		)
		(fp_poly
			(pts
				(xy -4.1529 3.4671) (xy -4.1529 -0.5842) (xy -3.6449 -0.5842) (xy -3.6449 2.4511) (xy 3.6449 2.4511)
				(xy 3.6449 -2.4511) (xy -3.6449 -2.4511) (xy -3.6449 -0.5969) (xy -4.1529 -0.5969) (xy -4.1529 -3.4671)
				(xy 4.1529 -3.4671) (xy 4.1529 3.4671)
			)
			(stroke
				(width 0)
				(type default)
			)
			(fill no)
			(layer "F.CrtYd")
		)
		(fp_rect
			(start -4.1529 3.4671)
			(end 4.1529 -3.4671)
			(stroke
				(width 0)
				(type default)
			)
			(fill no)
			(layer "F.Fab")
		)
		(pad "1" smd rect
			(at -2.54 2.005584)
			(size 1.651 1.905)
			(layers "F.Cu" "F.Mask" "F.Paste")
			(net "FM_OSC_50M_EN")
		)
		(pad "2" smd rect
			(at 2.54 2.005584)
			(size 1.651 1.905)
			(layers "F.Cu" "F.Mask" "F.Paste")
			(net "GND")
		)
		(pad "3" smd rect
			(at 2.54 -2.005584)
			(size 1.651 1.905)
			(layers "F.Cu" "F.Mask" "F.Paste")
			(net "50M_CLK_OUT")
		)
		(pad "4" smd rect
			(at -2.54 -2.005584)
			(size 1.651 1.905)
			(layers "F.Cu" "F.Mask" "F.Paste")
			(net "P3V3_STBY")
		)
		(zone
			(layer "F.Cu")
			(hatch none 0.5)
			(connect_pads
				(clearance 0)
			)
			(min_thickness 0.25)
			(keepout
				(tracks not_allowed)
				(vias allowed)
				(pads allowed)
				(copperpour not_allowed)
				(footprints allowed)
			)
			(placement
				(enabled no)
				(sheetname "")
			)
			(fill
				(thermal_gap 0.5)
				(thermal_bridge_width 0.5)
				(island_removal_mode 0)
			)
			(polygon
				(pts
					(xy 295.766236 -146.893788) (xy 295.766236 -148.341588) (xy 298.560236 -148.341588) (xy 298.560236 -146.893788)
				)
			)
		)
		(zone
			(layer "F.Cu")
			(hatch none 0.5)
			(connect_pads
				(clearance 0)
			)
			(min_thickness 0.25)
			(keepout
				(tracks allowed)
				(vias not_allowed)
				(pads allowed)
				(copperpour not_allowed)
				(footprints allowed)
			)
			(placement
				(enabled no)
				(sheetname "")
			)
			(fill
				(thermal_gap 0.5)
				(thermal_bridge_width 0.5)
				(island_removal_mode 0)
			)
			(polygon
				(pts
					(xy 295.448736 -144.659604) (xy 295.448736 -146.564604) (xy 293.797736 -146.564604) (xy 293.797736 -148.670772)
					(xy 295.448736 -148.670772) (xy 295.448736 -150.575772) (xy 298.877736 -150.575772) (xy 298.877736 -148.670772)
					(xy 300.528736 -148.670772) (xy 300.528736 -146.564604) (xy 298.877736 -146.564604) (xy 298.877736 -144.659604)
				)
			)
		)
	)
	(footprint ""
		(layer "F.Cu")
		(at 218.094814 -179.403248 90)
		(property "Reference" "R500"
			(at 0 0 90)
			(layer "F.SilkS")
			(hide yes)
			(effects
				(font
					(size 1.27 1.27)
				)
			)
		)
		(property "Value" "1KR2F-3-GP"
			(at 0.064008 -3.993896 90)
			(unlocked yes)
			(layer "F.Fab")
			(hide yes)
			(effects
				(font
					(size 1.016 1.016)
					(thickness 0.1524)
				)
			)
		)
		(property "Device Type" "R402H16"
			(at 0.064008 -5.517896 90)
			(unlocked yes)
			(layer "F.Fab")
			(hide yes)
			(effects
				(font
					(size 1.016 1.016)
					(thickness 0.1524)
				)
			)
		)
		(duplicate_pad_numbers_are_jumpers no)
		(fp_line
			(start 0.508 -0.9398)
			(end -0.508 -0.9398)
			(stroke
				(width 0.1524)
				(type default)
			)
			(layer "F.SilkS")
		)
		(fp_line
			(start -0.508 -0.9398)
			(end -0.508 0.9398)
			(stroke
				(width 0.1524)
				(type default)
			)
			(layer "F.SilkS")
		)
		(fp_rect
			(start -0.508 0.9398)
			(end 0.508 -0.9398)
			(stroke
				(width 0)
				(type default)
			)
			(fill no)
			(layer "F.CrtYd")
		)
		(fp_rect
			(start -0.508 0.9398)
			(end 0.508 -0.9398)
			(stroke
				(width 0)
				(type default)
			)
			(fill no)
			(layer "F.Fab")
		)
		(pad "1" smd custom
			(at 0 -0.4445 90)
			(size 0.1397 0.1397)
			(layers "F.Cu" "F.Mask" "F.Paste")
			(net "P3V3_STBY")
			(options
				(clearance outline)
				(anchor circle)
			)
			(primitives
				(gr_poly
					(pts
						(arc
							(start -0.1778 -0.2794)
							(mid -0.249642 -0.249642)
							(end -0.2794 -0.1778)
						)
						(arc
							(start -0.2794 0.1778)
							(mid -0.249642 0.249642)
							(end -0.1778 0.2794)
						)
						(arc
							(start 0.1778 0.2794)
							(mid 0.249642 0.249642)
							(end 0.2794 0.1778)
						)
						(arc
							(start 0.2794 -0.1778)
							(mid 0.249642 -0.249642)
							(end 0.1778 -0.2794)
						)
					)
					(width 0)
					(fill yes)
				)
			)
		)
		(pad "2" smd custom
			(at 0 0.4445 90)
			(size 0.1397 0.1397)
			(layers "F.Cu" "F.Mask" "F.Paste")
			(net "DIVIDER 1_IN_EXP")
			(options
				(clearance outline)
				(anchor circle)
			)
			(primitives
				(gr_poly
					(pts
						(arc
							(start -0.1778 -0.2794)
							(mid -0.249642 -0.249642)
							(end -0.2794 -0.1778)
						)
						(arc
							(start -0.2794 0.1778)
							(mid -0.249642 0.249642)
							(end -0.1778 0.2794)
						)
						(arc
							(start 0.1778 0.2794)
							(mid 0.249642 0.249642)
							(end 0.2794 0.1778)
						)
						(arc
							(start 0.2794 -0.1778)
							(mid 0.249642 -0.249642)
							(end 0.1778 -0.2794)
						)
					)
					(width 0)
					(fill yes)
				)
			)
		)
	)
)
